(kicad_pcb
	(version 20260206)
	(generator "pcbnew")
	(generator_version "10.0")
	(general
		(thickness 1.6)
		(legacy_teardrops no)
	)
	(paper "A4")
	(title_block
		(title "Bryce Canyon_R.DPB_16317-1_OCP.brd")
		(comment 1 "Bryce Canyon / footprints 163-165 of 2099")
	)
	(layers
		(0 "F.Cu" signal "TOP")
		(4 "In1.Cu" signal "L2GND")
		(6 "In2.Cu" signal "L3")
		(8 "In3.Cu" signal "L4VCC")
		(10 "In4.Cu" signal "L5VCC")
		(12 "In5.Cu" signal "L6")
		(14 "In6.Cu" signal "L7GND")
		(2 "B.Cu" signal "BOTTOM")
		(9 "F.Adhes" user "F.Adhesive")
		(11 "B.Adhes" user "B.Adhesive")
		(13 "F.Paste" user "Package Geometry/Pastemask Top")
		(15 "B.Paste" user "Package Geometry/Pastemask Bottom")
		(5 "F.SilkS" user "Ref Des/Silkscreen Top")
		(7 "B.SilkS" user "Ref Des/Silkscreen Bottom")
		(1 "F.Mask" user "Board Geometry/Soldermask Top")
		(3 "B.Mask" user "Board Geometry/Soldermask Bottom")
		(17 "Dwgs.User" user "User.Drawings")
		(19 "Cmts.User" user "User.Comments")
		(21 "Eco1.User" user "User.Eco1")
		(23 "Eco2.User" user "User.Eco2")
		(25 "Edge.Cuts" user "Board Geometry/Outline")
		(27 "Margin" user)
		(31 "F.CrtYd" user "Package Geometry/Place Bound Top")
		(29 "B.CrtYd" user "Package Geometry/Place Bound Bottom")
		(35 "F.Fab" user "Ref Des/Assembly Top")
		(33 "B.Fab" user "Ref Des/Assembly Bottom")
	)
	(footprint ""
		(layer "F.Cu")
		(at 261.960868 -209.582258 -90)
		(property "Reference" "R1294"
			(at 0 0 270)
			(layer "F.SilkS")
			(hide yes)
			(effects
				(font
					(size 1.27 1.27)
				)
			)
		)
		(property "Value" "1KR2J-1-GP"
			(at 0.064008 -3.993896 270)
			(unlocked yes)
			(layer "F.Fab")
			(hide yes)
			(effects
				(font
					(size 1.016 1.016)
					(thickness 0.1524)
				)
			)
		)
		(property "Device Type" "R402H16"
			(at 0.064008 -5.517896 270)
			(unlocked yes)
			(layer "F.Fab")
			(hide yes)
			(effects
				(font
					(size 1.016 1.016)
					(thickness 0.1524)
				)
			)
		)
		(duplicate_pad_numbers_are_jumpers no)
		(fp_line
			(start -0.508 -0.9398)
			(end -0.508 0.9398)
			(stroke
				(width 0.1524)
				(type default)
			)
			(layer "F.SilkS")
		)
		(fp_line
			(start 0.508 -0.9398)
			(end -0.508 -0.9398)
			(stroke
				(width 0.1524)
				(type default)
			)
			(layer "F.SilkS")
		)
		(fp_rect
			(start -0.508 0.9398)
			(end 0.508 -0.9398)
			(stroke
				(width 0)
				(type default)
			)
			(fill no)
			(layer "F.CrtYd")
		)
		(fp_rect
			(start -0.508 0.9398)
			(end 0.508 -0.9398)
			(stroke
				(width 0)
				(type default)
			)
			(fill no)
			(layer "F.Fab")
		)
		(pad "1" smd custom
			(at 0 -0.4445 270)
			(size 0.1397 0.1397)
			(layers "F.Cu" "F.Mask" "F.Paste")
			(net "P3V3_STBY_B")
			(options
				(clearance outline)
				(anchor circle)
			)
			(primitives
				(gr_poly
					(pts
						(arc
							(start -0.1778 -0.2794)
							(mid -0.249642 -0.249642)
							(end -0.2794 -0.1778)
						)
						(arc
							(start -0.2794 0.1778)
							(mid -0.249642 0.249642)
							(end -0.1778 0.2794)
						)
						(arc
							(start 0.1778 0.2794)
							(mid 0.249642 0.249642)
							(end 0.2794 0.1778)
						)
						(arc
							(start 0.2794 -0.1778)
							(mid 0.249642 -0.249642)
							(end 0.1778 -0.2794)
						)
					)
					(width 0)
					(fill yes)
				)
			)
		)
		(pad "2" smd custom
			(at 0 0.4445 270)
			(size 0.1397 0.1397)
			(layers "F.Cu" "F.Mask" "F.Paste")
			(net "I2C_DRIVE_B_PWR_SCL")
			(options
				(clearance outline)
				(anchor circle)
			)
			(primitives
				(gr_poly
					(pts
						(arc
							(start -0.1778 -0.2794)
							(mid -0.249642 -0.249642)
							(end -0.2794 -0.1778)
						)
						(arc
							(start -0.2794 0.1778)
							(mid -0.249642 0.249642)
							(end -0.1778 0.2794)
						)
						(arc
							(start 0.1778 0.2794)
							(mid 0.249642 0.249642)
							(end 0.2794 0.1778)
						)
						(arc
							(start 0.2794 -0.1778)
							(mid 0.249642 -0.249642)
							(end 0.1778 -0.2794)
						)
					)
					(width 0)
					(fill yes)
				)
			)
		)
	)
	(footprint ""
		(layer "F.Cu")
		(at 357.100124 -143.91005 -90)
		(property "Reference" "HDDSAS19"
			(at 0 0 270)
			(layer "F.SilkS")
			(hide yes)
			(effects
				(font
					(size 1.27 1.27)
				)
			)
		)
		(property "Value" "SKT-SAS15P-14P-45-GP"
			(at -20.7645 -8.9789 270)
			(unlocked yes)
			(layer "F.Fab")
			(hide yes)
			(effects
				(font
					(size 1.016 1.016)
					(thickness 0.1524)
				)
			)
		)
		(property "Device Type" "10120818-001C-TRLF"
			(at -20.7645 -10.5029 270)
			(unlocked yes)
			(layer "F.Fab")
			(hide yes)
			(effects
				(font
					(size 1.016 1.016)
					(thickness 0.1524)
				)
			)
		)
		(duplicate_pad_numbers_are_jumpers no)
		(fp_line
			(start 1.651 4.2926)
			(end 1.651 3.0099)
			(stroke
				(width 0.1524)
				(type default)
			)
			(layer "F.SilkS")
		)
		(fp_line
			(start 8.509 4.2926)
			(end 1.651 4.2926)
			(stroke
				(width 0.1524)
				(type default)
			)
			(layer "F.SilkS")
		)
		(fp_line
			(start -23.4188 3.0099)
			(end -23.4188 -3.2512)
			(stroke
				(width 0.1524)
				(type default)
			)
			(layer "F.SilkS")
		)
		(fp_line
			(start 1.651 3.0099)
			(end -23.4188 3.0099)
			(stroke
				(width 0.1524)
				(type default)
			)
			(layer "F.SilkS")
		)
		(fp_line
			(start 8.509 3.0099)
			(end 8.509 4.2926)
			(stroke
				(width 0.1524)
				(type default)
			)
			(layer "F.SilkS")
		)
		(fp_line
			(start 23.4188 3.0099)
			(end 8.509 3.0099)
			(stroke
				(width 0.1524)
				(type default)
			)
			(layer "F.SilkS")
		)
		(fp_line
			(start -23.4188 -3.2512)
			(end 23.4188 -3.2512)
			(stroke
				(width 0.1524)
				(type default)
			)
			(layer "F.SilkS")
		)
		(fp_line
			(start 23.4188 -3.2512)
			(end 23.4188 3.0099)
			(stroke
				(width 0.1524)
				(type default)
			)
			(layer "F.SilkS")
		)
		(fp_line
			(start 15.5067 -3.3401)
			(end 16.2687 -3.3401)
			(stroke
				(width 0.3302)
				(type default)
			)
			(layer "F.SilkS")
		)
		(fp_poly
			(pts
				(xy 15.868904 -3.230372) (xy 16.503904 -3.865372) (xy 15.233904 -3.865372)
			)
			(stroke
				(width 0)
				(type default)
			)
			(fill yes)
			(layer "F.SilkS")
		)
		(fp_poly
			(pts
				(xy -22.8727 -2.7559) (xy 22.8727 -2.7559) (xy 22.8727 2.7559) (xy 8.255 2.7559) (xy 8.255 3.5179)
				(xy 1.905 3.5179) (xy 1.905 2.7559) (xy -22.8727 2.7559)
			)
			(stroke
				(width 0)
				(type default)
			)
			(fill no)
			(layer "F.CrtYd")
		)
		(fp_poly
			(pts
				(xy 1.397 4.5466) (xy 1.397 3.2639) (xy -23.6728 3.2639) (xy -23.6728 -3.5052) (xy 23.6728 -3.5052)
				(xy 23.6728 -0.00635) (xy 22.8727 -0.00635) (xy 22.8727 -2.7559) (xy -22.8727 -2.7559) (xy -22.8727 2.7559)
				(xy 1.905 2.7559) (xy 1.905 3.5179) (xy 8.255 3.5179) (xy 8.255 2.7559) (xy 22.8727 2.7559) (xy 22.8727 0.00635)
				(xy 23.6728 0.00635) (xy 23.6728 3.2639) (xy 8.763 3.2639) (xy 8.763 4.5466)
			)
			(stroke
				(width 0)
				(type default)
			)
			(fill no)
			(layer "F.CrtYd")
		)
		(fp_poly
			(pts
				(xy 1.397 4.5466) (xy 1.397 3.2639) (xy -23.6728 3.2639) (xy -23.6728 -3.5052) (xy 23.6728 -3.5052)
				(xy 23.6728 3.2639) (xy 8.763 3.2639) (xy 8.763 4.5466)
			)
			(stroke
				(width 0)
				(type default)
			)
			(fill no)
			(layer "F.Fab")
		)
		(pad "" np_thru_hole circle
			(at -18.874994 0 270)
			(size 0.254 0.254)
			(drill 1.3462)
			(layers "*.Cu" "*.Mask")
			(clearance 0.9017)
			(thermal_gap 0.9017)
		)
		(pad "" np_thru_hole circle
			(at 18.874994 0 270)
			(size 0.254 0.254)
			(drill 0.9398)
			(layers "*.Cu" "*.Mask")
			(clearance 0.6985)
			(thermal_gap 0.6985)
		)
		(pad "G1" smd rect
			(at 21.874988 0 270)
			(size 2.5908 2.5908)
			(layers "F.Cu" "F.Mask" "F.Paste")
			(net "GND")
		)
		(pad "G2" smd rect
			(at -21.874988 0 270)
			(size 2.5908 2.5908)
			(layers "F.Cu" "F.Mask" "F.Paste")
			(net "GND")
		)
		(pad "P1" smd rect
			(at 1.905 -1.82499 270)
			(size 0.6096 2.3622)
			(layers "F.Cu" "F.Mask" "F.Paste")
			(net "Net_1704")
		)
		(pad "P2" smd rect
			(at 0.635 -1.82499 270)
			(size 0.6096 2.3622)
			(layers "F.Cu" "F.Mask" "F.Paste")
			(net "Net_1705")
		)
		(pad "P3" smd rect
			(at -0.635 -1.82499 270)
			(size 0.6096 2.3622)
			(layers "F.Cu" "F.Mask" "F.Paste")
			(net "Net_1706")
		)
		(pad "P4" smd rect
			(at -1.905 -1.82499 270)
			(size 0.6096 2.3622)
			(layers "F.Cu" "F.Mask" "F.Paste")
			(net "GND")
		)
		(pad "P5" smd rect
			(at -3.175 -1.82499 270)
			(size 0.6096 2.3622)
			(layers "F.Cu" "F.Mask" "F.Paste")
			(net "HDD_PRSNT_19")
		)
		(pad "P6" smd rect
			(at -4.445 -1.82499 270)
			(size 0.6096 2.3622)
			(layers "F.Cu" "F.Mask" "F.Paste")
			(net "GND")
		)
		(pad "P7" smd rect
			(at -5.715 -1.82499 270)
			(size 0.6096 2.3622)
			(layers "F.Cu" "F.Mask" "F.Paste")
			(net "5V_PRE_19")
		)
		(pad "P8" smd rect
			(at -6.985 -1.82499 270)
			(size 0.6096 2.3622)
			(layers "F.Cu" "F.Mask" "F.Paste")
			(net "P5V_HDD19")
		)
		(pad "P9" smd rect
			(at -8.255 -1.82499 270)
			(size 0.6096 2.3622)
			(layers "F.Cu" "F.Mask" "F.Paste")
			(net "P5V_HDD19")
		)
		(pad "P10" smd rect
			(at -9.525 -1.82499 270)
			(size 0.6096 2.3622)
			(layers "F.Cu" "F.Mask" "F.Paste")
			(net "GND")
		)
		(pad "P11" smd rect
			(at -10.795 -1.82499 270)
			(size 0.6096 2.3622)
			(layers "F.Cu" "F.Mask" "F.Paste")
			(net "ACT_HDD_19")
		)
		(pad "P12" smd rect
			(at -12.065 -1.82499 270)
			(size 0.6096 2.3622)
			(layers "F.Cu" "F.Mask" "F.Paste")
			(net "GND")
		)
		(pad "P13" smd rect
			(at -13.335 -1.82499 270)
			(size 0.6096 2.3622)
			(layers "F.Cu" "F.Mask" "F.Paste")
			(net "12V_PRE_19")
		)
		(pad "P14" smd rect
			(at -14.605 -1.82499 270)
			(size 0.6096 2.3622)
			(layers "F.Cu" "F.Mask" "F.Paste")
			(net "P12V_HDD19")
		)
		(pad "P15" smd rect
			(at -15.875 -1.82499 270)
			(size 0.6096 2.3622)
			(layers "F.Cu" "F.Mask" "F.Paste")
			(net "P12V_HDD19")
		)
		(pad "S1" smd rect
			(at 15.875 -1.82499 270)
			(size 0.6096 2.3622)
			(layers "F.Cu" "F.Mask" "F.Paste")
			(net "GND")
		)
		(pad "S2" smd rect
			(at 14.605 -1.82499 270)
			(size 0.6096 2.3622)
			(layers "F.Cu" "F.Mask" "F.Paste")
			(net "SAS_HDD_RX_P19")
		)
		(pad "S3" smd rect
			(at 13.335 -1.82499 270)
			(size 0.6096 2.3622)
			(layers "F.Cu" "F.Mask" "F.Paste")
			(net "SAS_HDD_RX_N19")
		)
		(pad "S4" smd rect
			(at 12.065 -1.82499 270)
			(size 0.6096 2.3622)
			(layers "F.Cu" "F.Mask" "F.Paste")
			(net "GND")
		)
		(pad "S5" smd rect
			(at 10.795 -1.82499 270)
			(size 0.6096 2.3622)
			(layers "F.Cu" "F.Mask" "F.Paste")
			(net "PHY_DRV_B_TO_SCC_B_19_DN")
		)
		(pad "S6" smd rect
			(at 9.525 -1.82499 270)
			(size 0.6096 2.3622)
			(layers "F.Cu" "F.Mask" "F.Paste")
			(net "PHY_DRV_B_TO_SCC_B_19_DP")
		)
		(pad "S7" smd rect
			(at 8.255 -1.82499 270)
			(size 0.6096 2.3622)
			(layers "F.Cu" "F.Mask" "F.Paste")
			(net "GND")
		)
		(pad "S8" smd rect
			(at 7.480046 2.845054 270)
			(size 0.508 2.3622)
			(layers "F.Cu" "F.Mask" "F.Paste")
			(net "GND")
		)
		(pad "S9" smd rect
			(at 6.679946 2.845054 270)
			(size 0.508 2.3622)
			(layers "F.Cu" "F.Mask" "F.Paste")
			(net "Net_443")
		)
		(pad "S10" smd rect
			(at 5.8801 2.845054 270)
			(size 0.508 2.3622)
			(layers "F.Cu" "F.Mask" "F.Paste")
			(net "Net_335")
		)
		(pad "S11" smd rect
			(at 5.08 2.845054 270)
			(size 0.508 2.3622)
			(layers "F.Cu" "F.Mask" "F.Paste")
			(net "GND")
		)
		(pad "S12" smd rect
			(at 4.2799 2.845054 270)
			(size 0.508 2.3622)
			(layers "F.Cu" "F.Mask" "F.Paste")
			(net "Net_371")
		)
		(pad "S13" smd rect
			(at 3.480054 2.845054 270)
			(size 0.508 2.3622)
			(layers "F.Cu" "F.Mask" "F.Paste")
			(net "Net_407")
		)
		(pad "S14" smd rect
			(at 2.679954 2.845054 270)
			(size 0.508 2.3622)
			(layers "F.Cu" "F.Mask" "F.Paste")
			(net "GND")
		)
		(zone
			(layer "F.Cu")
			(hatch none 0.5)
			(connect_pads
				(clearance 0)
			)
			(min_thickness 0.25)
			(keepout
				(tracks allowed)
				(vias not_allowed)
				(pads allowed)
				(copperpour not_allowed)
				(footprints allowed)
			)
			(placement
				(enabled no)
				(sheetname "")
			)
			(fill
				(thermal_gap 0.5)
				(thermal_bridge_width 0.5)
				(island_removal_mode 0)
			)
			(polygon
				(pts
					(xy 360.757724 -160.64865) (xy 353.683824 -160.64865) (xy 353.683824 -167.58285) (xy 354.788724 -167.58285)
					(xy 354.788724 -163.46805) (xy 359.411524 -163.46805) (xy 359.411524 -167.58285) (xy 360.757724 -167.58285)
				)
			)
		)
		(zone
			(layer "F.Cu")
			(hatch none 0.5)
			(connect_pads
				(clearance 0)
			)
			(min_thickness 0.25)
			(keepout
				(tracks not_allowed)
				(vias allowed)
				(pads allowed)
				(copperpour not_allowed)
				(footprints allowed)
			)
			(placement
				(enabled no)
				(sheetname "")
			)
			(fill
				(thermal_gap 0.5)
				(thermal_bridge_width 0.5)
				(island_removal_mode 0)
			)
			(polygon
				(pts
					(xy 360.757724 -160.64865) (xy 353.683824 -160.64865) (xy 353.683824 -167.58285) (xy 354.788724 -167.58285)
					(xy 354.788724 -163.46805) (xy 359.411524 -163.46805) (xy 359.411524 -167.58285) (xy 360.757724 -167.58285)
				)
			)
		)
		(zone
			(layer "F.Cu")
			(hatch none 0.5)
			(connect_pads
				(clearance 0)
			)
			(min_thickness 0.25)
			(keepout
				(tracks not_allowed)
				(vias allowed)
				(pads allowed)
				(copperpour not_allowed)
				(footprints allowed)
			)
			(placement
				(enabled no)
				(sheetname "")
			)
			(fill
				(thermal_gap 0.5)
				(thermal_bridge_width 0.5)
				(island_removal_mode 0)
			)
			(polygon
				(pts
					(xy 360.757724 -127.17145) (xy 353.683824 -127.17145) (xy 353.683824 -120.23725) (xy 354.788724 -120.23725)
					(xy 354.788724 -124.35205) (xy 359.411524 -124.35205) (xy 359.411524 -120.23725) (xy 360.757724 -120.23725)
				)
			)
		)
		(zone
			(layer "F.Cu")
			(hatch none 0.5)
			(connect_pads
				(clearance 0)
			)
			(min_thickness 0.25)
			(keepout
				(tracks allowed)
				(vias not_allowed)
				(pads allowed)
				(copperpour not_allowed)
				(footprints allowed)
			)
			(placement
				(enabled no)
				(sheetname "")
			)
			(fill
				(thermal_gap 0.5)
				(thermal_bridge_width 0.5)
				(island_removal_mode 0)
			)
			(polygon
				(pts
					(xy 360.757724 -127.17145) (xy 353.683824 -127.17145) (xy 353.683824 -120.23725) (xy 354.788724 -120.23725)
					(xy 354.788724 -124.35205) (xy 359.411524 -124.35205) (xy 359.411524 -120.23725) (xy 360.757724 -120.23725)
				)
			)
		)
		(zone
			(layers "F.Cu" "B.Cu" "In1.Cu" "In2.Cu" "In3.Cu" "In4.Cu" "In5.Cu" "In6.Cu")
			(hatch none 0.5)
			(connect_pads
				(clearance 0)
			)
			(min_thickness 0.25)
			(keepout
				(tracks not_allowed)
				(vias allowed)
				(pads allowed)
				(copperpour not_allowed)
				(footprints allowed)
			)
			(placement
				(enabled no)
				(sheetname "")
			)
			(fill
				(thermal_gap 0.5)
				(thermal_bridge_width 0.5)
				(island_removal_mode 0)
			)
			(polygon
				(pts
					(arc
						(start 357.874824 -125.035056)
						(mid 356.325424 -125.035056)
						(end 357.874824 -125.035056)
					)
				)
			)
		)
		(zone
			(layers "F.Cu" "B.Cu" "In1.Cu" "In2.Cu" "In3.Cu" "In4.Cu" "In5.Cu" "In6.Cu")
			(hatch none 0.5)
			(connect_pads
				(clearance 0)
			)
			(min_thickness 0.25)
			(keepout
				(tracks not_allowed)
				(vias allowed)
				(pads allowed)
				(copperpour not_allowed)
				(footprints allowed)
			)
			(placement
				(enabled no)
				(sheetname "")
			)
			(fill
				(thermal_gap 0.5)
				(thermal_bridge_width 0.5)
				(island_removal_mode 0)
			)
			(polygon
				(pts
					(arc
						(start 358.078024 -162.785044)
						(mid 356.122224 -162.785044)
						(end 358.078024 -162.785044)
					)
				)
			)
		)
	)
	(footprint ""
		(layer "F.Cu")
		(at 310.4134 -340.812882 180)
		(property "Reference" "R104"
			(at 0 0 180)
			(layer "F.SilkS")
			(hide yes)
			(effects
				(font
					(size 1.27 1.27)
				)
			)
		)
		(property "Value" "0R2J-2-GP"
			(at 0.064008 -3.993896 180)
			(unlocked yes)
			(layer "F.Fab")
			(hide yes)
			(effects
				(font
					(size 1.016 1.016)
					(thickness 0.1524)
				)
			)
		)
		(property "Device Type" "R402H16"
			(at 0.064008 -5.517896 180)
			(unlocked yes)
			(layer "F.Fab")
			(hide yes)
			(effects
				(font
					(size 1.016 1.016)
					(thickness 0.1524)
				)
			)
		)
		(duplicate_pad_numbers_are_jumpers no)
		(fp_line
			(start 0.508 -0.9398)
			(end -0.508 -0.9398)
			(stroke
				(width 0.1524)
				(type default)
			)
			(layer "F.SilkS")
		)
		(fp_line
			(start -0.508 -0.9398)
			(end -0.508 0.9398)
			(stroke
				(width 0.1524)
				(type default)
			)
			(layer "F.SilkS")
		)
		(fp_rect
			(start -0.508 0.9398)
			(end 0.508 -0.9398)
			(stroke
				(width 0)
				(type default)
			)
			(fill no)
			(layer "F.CrtYd")
		)
		(fp_rect
			(start -0.508 0.9398)
			(end 0.508 -0.9398)
			(stroke
				(width 0)
				(type default)
			)
			(fill no)
			(layer "F.Fab")
		)
		(pad "1" smd custom
			(at 0 -0.4445 180)
			(size 0.1397 0.1397)
			(layers "F.Cu" "F.Mask" "F.Paste")
			(net "PWM_OUT_D_R")
			(options
				(clearance outline)
				(anchor circle)
			)
			(primitives
				(gr_poly
					(pts
						(arc
							(start -0.1778 -0.2794)
							(mid -0.249642 -0.249642)
							(end -0.2794 -0.1778)
						)
						(arc
							(start -0.2794 0.1778)
							(mid -0.249642 0.249642)
							(end -0.1778 0.2794)
						)
						(arc
							(start 0.1778 0.2794)
							(mid 0.249642 0.249642)
							(end 0.2794 0.1778)
						)
						(arc
							(start 0.2794 -0.1778)
							(mid 0.249642 -0.249642)
							(end 0.1778 -0.2794)
						)
					)
					(width 0)
					(fill yes)
				)
			)
		)
		(pad "2" smd custom
			(at 0 0.4445 180)
			(size 0.1397 0.1397)
			(layers "F.Cu" "F.Mask" "F.Paste")
			(net "PWM_OUT_D")
			(options
				(clearance outline)
				(anchor circle)
			)
			(primitives
				(gr_poly
					(pts
						(arc
							(start -0.1778 -0.2794)
							(mid -0.249642 -0.249642)
							(end -0.2794 -0.1778)
						)
						(arc
							(start -0.2794 0.1778)
							(mid -0.249642 0.249642)
							(end -0.1778 0.2794)
						)
						(arc
							(start 0.1778 0.2794)
							(mid 0.249642 0.249642)
							(end 0.2794 0.1778)
						)
						(arc
							(start 0.2794 -0.1778)
							(mid 0.249642 -0.249642)
							(end 0.1778 -0.2794)
						)
					)
					(width 0)
					(fill yes)
				)
			)
		)
	)
)
